# ZAIUS-LV_CARD-EVT1-X00-BOM-X01_20160825.xls — Component Qual Tracker (bom)
|  |  |  |  |  |  |  |  | Part to be included on following build: |  |  |  |  |  |
| Item No. | Part Group | Single/Sole/Multi | Item Description | ODM P/N | Dell PN | Vendor | Vendor P/N | X00 Build | X01 Build | X02 Build | Qual Build | Qualification Target Date | Qualification Complete Date |
|  | VR Controllers |  |  |  |  | Vendor #1 |  |  |  |  |  |  |  |
|  |  |  |  |  |  | Vendor #2 |  |  |  |  |  |  |  |
|  | FETS |  |  |  |  | Vendor #1 |  |  |  |  |  |  |  |
|  |  |  |  |  |  | Vendor #2 |  |  |  |  |  |  |  |
|  | INDUCTORS |  |  |  |  | Vendor #1 |  |  |  |  |  |  |  |
|  |  |  |  |  |  | Vendor #2 |  |  |  |  |  |  |  |
|  | VREG CAPS |  |  |  |  | Vendor #1 |  |  |  |  |  |  |  |
|  |  |  |  |  |  | Vendor #2 |  |  |  |  |  |  |  |
|  | CRYSTALS |  |  |  |  | Vendor #1 |  |  |  |  |  |  |  |
|  |  |  |  |  |  | Vendor #2 |  |  |  |  |  |  |  |
|  | CONNECTORS |  |  |  |  | Vendor #1 |  |  |  |  |  |  |  |
|  |  |  |  |  |  | Vendor #2 |  |  |  |  |  |  |  |
|  | IC'S |  |  |  |  | Vendor #1 |  |  |  |  |  |  |  |
|  |  |  |  |  |  | Vendor #2 |  |  |  |  |  |  |  |
|  | MISC. |  |  |  |  | Vendor #1 |  |  |  |  |  |  |  |
|  | (HEATSINKS) |  |  |  |  | Vendor #2 |  |  |  |  |  |  |  |
